# S9S_MB_2U (Grand Teton) — schematic netlist excerpt (pin names and nets, part order shuffled) for the footprints in the layout excerpt that follows; sources: Cadence DE-HDL packaged netlist, KiCad conversion of 03242023_DA0F0TMBIJ0_F0T_Motherboard_J_brd_V01_OCP.brd

PR2222  Q_RES  34.8K 1% CHIP  pkg 0402LF  page 300 : A = PVNN_MAIN_CPU1_CS ; B = GND
R3051  Q_RES  0 5% CHIP  pkg 0402LF  page 228 : A = IRQ_SML1_PMBUS_ALERT_R_N ; B = IRQ_SML1_PMBUS_ALERT_N

(kicad_pcb
	(version 20260206)
	(generator "pcbnew")
	(generator_version "10.0")
	(general
		(thickness 1.6)
		(legacy_teardrops no)
	)
	(paper "A4")
	(title_block
		(title "03242023_DA0F0TMBIJ0_F0T_Motherboard_J_brd_V01_OCP.brd")
		(comment 1 "Grand Teton / footprints 1910-1911 of 6105")
	)
	(layers
		(0 "F.Cu" signal "TOP")
		(4 "In1.Cu" signal "GND")
		(6 "In2.Cu" signal "IN1")
		(8 "In3.Cu" signal "GND1")
		(10 "In4.Cu" signal "IN2")
		(12 "In5.Cu" signal "GND2")
		(14 "In6.Cu" signal "IN3")
		(16 "In7.Cu" signal "GND3")
		(18 "In8.Cu" signal "VCC")
		(20 "In9.Cu" signal "VCC1")
		(22 "In10.Cu" signal "GND4")
		(24 "In11.Cu" signal "IN4")
		(26 "In12.Cu" signal "GND5")
		(28 "In13.Cu" signal "IN5")
		(30 "In14.Cu" signal "GND6")
		(32 "In15.Cu" signal "IN6")
		(34 "In16.Cu" signal "GND7")
		(2 "B.Cu" signal "BOTTOM")
		(9 "F.Adhes" user "F.Adhesive")
		(11 "B.Adhes" user "B.Adhesive")
		(13 "F.Paste" user "Package Geometry/Pastemask Top")
		(15 "B.Paste" user "Package Geometry/Pastemask Bottom")
		(5 "F.SilkS" user "Ref Des/Silkscreen Top")
		(7 "B.SilkS" user "Ref Des/Silkscreen Bottom")
		(1 "F.Mask" user "Board Geometry/Soldermask Top")
		(3 "B.Mask" user "Board Geometry/Soldermask Bottom")
		(17 "Dwgs.User" user "User.Drawings")
		(19 "Cmts.User" user "User.Comments")
		(21 "Eco1.User" user "User.Eco1")
		(23 "Eco2.User" user "User.Eco2")
		(25 "Edge.Cuts" user "Board Geometry/Outline")
		(27 "Margin" user)
		(31 "F.CrtYd" user "Package Geometry/Place Bound Top")
		(29 "B.CrtYd" user "Package Geometry/Place Bound Bottom")
		(35 "F.Fab" user "Ref Des/Assembly Top")
		(33 "B.Fab" user "Ref Des/Assembly Bottom")
	)
	(footprint ""
		(layer "F.Cu")
		(at 20.831556 -178.077368 -90)
		(property "Reference" "PR2222"
			(at 0 0 270)
			(layer "F.SilkS")
			(hide yes)
			(effects
				(font
					(size 1.27 1.27)
				)
			)
		)
		(property "Value" ""
			(at 0 0 270)
			(layer "F.Fab")
			(effects
				(font
					(size 1.27 1.27)
				)
			)
		)
		(duplicate_pad_numbers_are_jumpers no)
		(fp_line
			(start -0.7874 0.4064)
			(end -0.7874 -0.4064)
			(stroke
				(width 0.1524)
				(type default)
			)
			(layer "F.SilkS")
		)
		(fp_line
			(start 0.7874 0.4064)
			(end -0.7874 0.4064)
			(stroke
				(width 0.1524)
				(type default)
			)
			(layer "F.SilkS")
		)
		(fp_line
			(start -0.7874 -0.4064)
			(end 0.7874 -0.4064)
			(stroke
				(width 0.1524)
				(type default)
			)
			(layer "F.SilkS")
		)
		(fp_line
			(start 0.7874 -0.4064)
			(end 0.7874 0.4064)
			(stroke
				(width 0.1524)
				(type default)
			)
			(layer "F.SilkS")
		)
		(fp_line
			(start -0.67945 0.3048)
			(end -0.67945 -0.305054)
			(stroke
				(width 0.1)
				(type default)
			)
			(layer "F.Fab")
		)
		(fp_line
			(start -0.12065 0.3048)
			(end -0.67945 0.3048)
			(stroke
				(width 0.1)
				(type default)
			)
			(layer "F.Fab")
		)
		(fp_line
			(start 0.120396 0.3048)
			(end 0.120396 0.2794)
			(stroke
				(width 0.1)
				(type default)
			)
			(layer "F.Fab")
		)
		(fp_line
			(start 0.67945 0.3048)
			(end 0.120396 0.3048)
			(stroke
				(width 0.1)
				(type default)
			)
			(layer "F.Fab")
		)
		(fp_line
			(start -0.12065 0.2794)
			(end -0.12065 0.3048)
			(stroke
				(width 0.1)
				(type default)
			)
			(layer "F.Fab")
		)
		(fp_line
			(start 0.120396 0.2794)
			(end -0.12065 0.2794)
			(stroke
				(width 0.1)
				(type default)
			)
			(layer "F.Fab")
		)
		(fp_line
			(start -0.12065 -0.2794)
			(end 0.12065 -0.2794)
			(stroke
				(width 0.1)
				(type default)
			)
			(layer "F.Fab")
		)
		(fp_line
			(start 0.12065 -0.2794)
			(end 0.12065 -0.3048)
			(stroke
				(width 0.1)
				(type default)
			)
			(layer "F.Fab")
		)
		(fp_line
			(start 0.12065 -0.3048)
			(end 0.67945 -0.3048)
			(stroke
				(width 0.1)
				(type default)
			)
			(layer "F.Fab")
		)
		(fp_line
			(start 0.67945 -0.3048)
			(end 0.67945 0.3048)
			(stroke
				(width 0.1)
				(type default)
			)
			(layer "F.Fab")
		)
		(fp_line
			(start -0.67945 -0.305054)
			(end -0.12065 -0.305054)
			(stroke
				(width 0.1)
				(type default)
			)
			(layer "F.Fab")
		)
		(fp_line
			(start -0.12065 -0.305054)
			(end -0.12065 -0.2794)
			(stroke
				(width 0.1)
				(type default)
			)
			(layer "F.Fab")
		)
		(pad "1" smd circle
			(at -0.40005 0 270)
			(size 0 0)
			(layers "F.Cu" "F.Mask" "F.Paste")
			(net "PVNN_MAIN_CPU1_CS")
		)
		(pad "2" smd circle
			(at 0.40005 0 270)
			(size 0 0)
			(layers "F.Cu" "F.Mask" "F.Paste")
			(net "GND")
		)
	)
	(footprint ""
		(layer "F.Cu")
		(at 27.81681 -55.015384)
		(property "Reference" "R3051"
			(at 0 0 0)
			(layer "F.SilkS")
			(hide yes)
			(effects
				(font
					(size 1.27 1.27)
				)
			)
		)
		(property "Value" ""
			(at 0 0 0)
			(layer "F.Fab")
			(effects
				(font
					(size 1.27 1.27)
				)
			)
		)
		(duplicate_pad_numbers_are_jumpers no)
		(fp_line
			(start -0.7874 -0.4064)
			(end 0.7874 -0.4064)
			(stroke
				(width 0.1524)
				(type default)
			)
			(layer "F.SilkS")
		)
		(fp_line
			(start -0.7874 0.4064)
			(end -0.7874 -0.4064)
			(stroke
				(width 0.1524)
				(type default)
			)
			(layer "F.SilkS")
		)
		(fp_line
			(start 0.7874 -0.4064)
			(end 0.7874 0.4064)
			(stroke
				(width 0.1524)
				(type default)
			)
			(layer "F.SilkS")
		)
		(fp_line
			(start 0.7874 0.4064)
			(end -0.7874 0.4064)
			(stroke
				(width 0.1524)
				(type default)
			)
			(layer "F.SilkS")
		)
		(fp_line
			(start -0.67945 -0.305054)
			(end -0.12065 -0.305054)
			(stroke
				(width 0.1)
				(type default)
			)
			(layer "F.Fab")
		)
		(fp_line
			(start -0.67945 0.3048)
			(end -0.67945 -0.305054)
			(stroke
				(width 0.1)
				(type default)
			)
			(layer "F.Fab")
		)
		(fp_line
			(start -0.12065 -0.305054)
			(end -0.12065 -0.2794)
			(stroke
				(width 0.1)
				(type default)
			)
			(layer "F.Fab")
		)
		(fp_line
			(start -0.12065 -0.2794)
			(end 0.12065 -0.2794)
			(stroke
				(width 0.1)
				(type default)
			)
			(layer "F.Fab")
		)
		(fp_line
			(start -0.12065 0.2794)
			(end -0.12065 0.3048)
			(stroke
				(width 0.1)
				(type default)
			)
			(layer "F.Fab")
		)
		(fp_line
			(start -0.12065 0.3048)
			(end -0.67945 0.3048)
			(stroke
				(width 0.1)
				(type default)
			)
			(layer "F.Fab")
		)
		(fp_line
			(start 0.120396 0.2794)
			(end -0.12065 0.2794)
			(stroke
				(width 0.1)
				(type default)
			)
			(layer "F.Fab")
		)
		(fp_line
			(start 0.120396 0.3048)
			(end 0.120396 0.2794)
			(stroke
				(width 0.1)
				(type default)
			)
			(layer "F.Fab")
		)
		(fp_line
			(start 0.12065 -0.3048)
			(end 0.67945 -0.3048)
			(stroke
				(width 0.1)
				(type default)
			)
			(layer "F.Fab")
		)
		(fp_line
			(start 0.12065 -0.2794)
			(end 0.12065 -0.3048)
			(stroke
				(width 0.1)
				(type default)
			)
			(layer "F.Fab")
		)
		(fp_line
			(start 0.67945 -0.3048)
			(end 0.67945 0.3048)
			(stroke
				(width 0.1)
				(type default)
			)
			(layer "F.Fab")
		)
		(fp_line
			(start 0.67945 0.3048)
			(end 0.120396 0.3048)
			(stroke
				(width 0.1)
				(type default)
			)
			(layer "F.Fab")
		)
		(pad "1" smd circle
			(at -0.40005 0)
			(size 0 0)
			(layers "F.Cu" "F.Mask" "F.Paste")
			(net "IRQ_SML1_PMBUS_ALERT_R_N")
		)
		(pad "2" smd circle
			(at 0.40005 0)
			(size 0 0)
			(layers "F.Cu" "F.Mask" "F.Paste")
			(net "IRQ_SML1_PMBUS_ALERT_N")
		)
	)
)
